(kicad_pcb
	(version 20260206)
	(generator "pcbnew")
	(generator_version "10.0")
	(general
		(thickness 1.6)
		(legacy_teardrops no)
	)
	(paper "A4")
	(title_block
		(title "15969-1a.1015WZS0858.brd")
		(comment 1 "Tioga Pass / footprints 38-43 of 295")
	)
	(layers
		(0 "F.Cu" signal "TOP")
		(4 "In1.Cu" signal "L2GND")
		(6 "In2.Cu" signal "L3")
		(8 "In3.Cu" signal "L4")
		(10 "In4.Cu" signal "L5GND")
		(2 "B.Cu" signal "BOTTOM")
		(9 "F.Adhes" user "F.Adhesive")
		(11 "B.Adhes" user "B.Adhesive")
		(13 "F.Paste" user "Package Geometry/Pastemask Top")
		(15 "B.Paste" user "Package Geometry/Pastemask Bottom")
		(5 "F.SilkS" user "Ref Des/Silkscreen Top")
		(7 "B.SilkS" user "Ref Des/Silkscreen Bottom")
		(1 "F.Mask" user "Board Geometry/Soldermask Top")
		(3 "B.Mask" user "Board Geometry/Soldermask Bottom")
		(17 "Dwgs.User" user "User.Drawings")
		(19 "Cmts.User" user "User.Comments")
		(21 "Eco1.User" user "User.Eco1")
		(23 "Eco2.User" user "User.Eco2")
		(25 "Edge.Cuts" user "Board Geometry/Outline")
		(27 "Margin" user)
		(31 "F.CrtYd" user "Package Geometry/Place Bound Top")
		(29 "B.CrtYd" user "Package Geometry/Place Bound Bottom")
		(35 "F.Fab" user "Ref Des/Assembly Top")
		(33 "B.Fab" user "Ref Des/Assembly Bottom")
	)
	(footprint ""
		(layer "F.Cu")
		(at 26.5176 -26.6446 90)
		(property "Reference" "R93"
			(at 0 0 90)
			(layer "F.SilkS")
			(hide yes)
			(effects
				(font
					(size 1.27 1.27)
				)
			)
		)
		(property "Value" "10KR2F-2-GP"
			(at 0.064008 -3.993896 90)
			(unlocked yes)
			(layer "F.Fab")
			(hide yes)
			(effects
				(font
					(size 1.016 1.016)
					(thickness 0.1524)
				)
			)
		)
		(property "Device Type" "R402H16"
			(at 0.064008 -5.517896 90)
			(unlocked yes)
			(layer "F.Fab")
			(hide yes)
			(effects
				(font
					(size 1.016 1.016)
					(thickness 0.1524)
				)
			)
		)
		(duplicate_pad_numbers_are_jumpers no)
		(fp_line
			(start 0.508 -0.9398)
			(end -0.508 -0.9398)
			(stroke
				(width 0.1524)
				(type default)
			)
			(layer "F.SilkS")
		)
		(fp_line
			(start -0.508 -0.9398)
			(end -0.508 0.9398)
			(stroke
				(width 0.1524)
				(type default)
			)
			(layer "F.SilkS")
		)
		(fp_rect
			(start -0.508 0.9398)
			(end 0.508 -0.9398)
			(stroke
				(width 0)
				(type default)
			)
			(fill no)
			(layer "F.CrtYd")
		)
		(fp_rect
			(start -0.508 0.9398)
			(end 0.508 -0.9398)
			(stroke
				(width 0)
				(type default)
			)
			(fill no)
			(layer "F.Fab")
		)
		(pad "1" smd custom
			(at 0 -0.4445 90)
			(size 0.1397 0.1397)
			(layers "F.Cu" "F.Mask" "F.Paste")
			(net "SLOT3_VMONITOR_A0")
			(options
				(clearance outline)
				(anchor circle)
			)
			(primitives
				(gr_poly
					(pts
						(arc
							(start -0.1778 -0.2794)
							(mid -0.249642 -0.249642)
							(end -0.2794 -0.1778)
						)
						(arc
							(start -0.2794 0.1778)
							(mid -0.249642 0.249642)
							(end -0.1778 0.2794)
						)
						(arc
							(start 0.1778 0.2794)
							(mid 0.249642 0.249642)
							(end 0.2794 0.1778)
						)
						(arc
							(start 0.2794 -0.1778)
							(mid 0.249642 -0.249642)
							(end 0.1778 -0.2794)
						)
					)
					(width 0)
					(fill yes)
				)
			)
		)
		(pad "2" smd custom
			(at 0 0.4445 90)
			(size 0.1397 0.1397)
			(layers "F.Cu" "F.Mask" "F.Paste")
			(net "GND")
			(options
				(clearance outline)
				(anchor circle)
			)
			(primitives
				(gr_poly
					(pts
						(arc
							(start -0.1778 -0.2794)
							(mid -0.249642 -0.249642)
							(end -0.2794 -0.1778)
						)
						(arc
							(start -0.2794 0.1778)
							(mid -0.249642 0.249642)
							(end -0.1778 0.2794)
						)
						(arc
							(start 0.1778 0.2794)
							(mid 0.249642 0.249642)
							(end 0.2794 0.1778)
						)
						(arc
							(start 0.2794 -0.1778)
							(mid 0.249642 -0.249642)
							(end 0.1778 -0.2794)
						)
					)
					(width 0)
					(fill yes)
				)
			)
		)
	)
	(footprint ""
		(layer "F.Cu")
		(at 26.5176 -25.6032 90)
		(property "Reference" "R92"
			(at 0 0 90)
			(layer "F.SilkS")
			(hide yes)
			(effects
				(font
					(size 1.27 1.27)
				)
			)
		)
		(property "Value" "10KR2F-2-GP"
			(at 0.064008 -3.993896 90)
			(unlocked yes)
			(layer "F.Fab")
			(hide yes)
			(effects
				(font
					(size 1.016 1.016)
					(thickness 0.1524)
				)
			)
		)
		(property "Device Type" "R402H16"
			(at 0.064008 -5.517896 90)
			(unlocked yes)
			(layer "F.Fab")
			(hide yes)
			(effects
				(font
					(size 1.016 1.016)
					(thickness 0.1524)
				)
			)
		)
		(duplicate_pad_numbers_are_jumpers no)
		(fp_line
			(start 0.508 -0.9398)
			(end -0.508 -0.9398)
			(stroke
				(width 0.1524)
				(type default)
			)
			(layer "F.SilkS")
		)
		(fp_line
			(start -0.508 -0.9398)
			(end -0.508 0.9398)
			(stroke
				(width 0.1524)
				(type default)
			)
			(layer "F.SilkS")
		)
		(fp_rect
			(start -0.508 0.9398)
			(end 0.508 -0.9398)
			(stroke
				(width 0)
				(type default)
			)
			(fill no)
			(layer "F.CrtYd")
		)
		(fp_rect
			(start -0.508 0.9398)
			(end 0.508 -0.9398)
			(stroke
				(width 0)
				(type default)
			)
			(fill no)
			(layer "F.Fab")
		)
		(pad "1" smd custom
			(at 0 -0.4445 90)
			(size 0.1397 0.1397)
			(layers "F.Cu" "F.Mask" "F.Paste")
			(net "SLOT3_VMONITOR_A1")
			(options
				(clearance outline)
				(anchor circle)
			)
			(primitives
				(gr_poly
					(pts
						(arc
							(start -0.1778 -0.2794)
							(mid -0.249642 -0.249642)
							(end -0.2794 -0.1778)
						)
						(arc
							(start -0.2794 0.1778)
							(mid -0.249642 0.249642)
							(end -0.1778 0.2794)
						)
						(arc
							(start 0.1778 0.2794)
							(mid 0.249642 0.249642)
							(end 0.2794 0.1778)
						)
						(arc
							(start 0.2794 -0.1778)
							(mid 0.249642 -0.249642)
							(end 0.1778 -0.2794)
						)
					)
					(width 0)
					(fill yes)
				)
			)
		)
		(pad "2" smd custom
			(at 0 0.4445 90)
			(size 0.1397 0.1397)
			(layers "F.Cu" "F.Mask" "F.Paste")
			(net "GND")
			(options
				(clearance outline)
				(anchor circle)
			)
			(primitives
				(gr_poly
					(pts
						(arc
							(start -0.1778 -0.2794)
							(mid -0.249642 -0.249642)
							(end -0.2794 -0.1778)
						)
						(arc
							(start -0.2794 0.1778)
							(mid -0.249642 0.249642)
							(end -0.1778 0.2794)
						)
						(arc
							(start 0.1778 0.2794)
							(mid 0.249642 0.249642)
							(end 0.2794 0.1778)
						)
						(arc
							(start 0.2794 -0.1778)
							(mid 0.249642 -0.249642)
							(end 0.1778 -0.2794)
						)
					)
					(width 0)
					(fill yes)
				)
			)
		)
	)
	(footprint ""
		(layer "F.Cu")
		(at 6.999986 -25.584912 -90)
		(property "Reference" "H1"
			(at 0 0 270)
			(layer "F.SilkS")
			(hide yes)
			(effects
				(font
					(size 1.27 1.27)
				)
			)
		)
		(property "Value" "STFT363B238R224H453-GP"
			(at 7.0612 1.4605 270)
			(unlocked yes)
			(layer "F.Fab")
			(hide yes)
			(effects
				(font
					(size 1.016 1.016)
					(thickness 0.1524)
				)
			)
		)
		(property "Device Type" "STFT363B238R224H453"
			(at 7.0612 -0.0635 270)
			(unlocked yes)
			(layer "F.Fab")
			(hide yes)
			(effects
				(font
					(size 1.016 1.016)
					(thickness 0.1524)
				)
			)
		)
		(duplicate_pad_numbers_are_jumpers no)
		(fp_circle
			(center 0 0)
			(end 0 -5.3594)
			(stroke
				(width 0.3048)
				(type default)
			)
			(fill no)
			(layer "F.SilkS")
		)
		(fp_poly
			(pts
				(arc
					(start 0 -3.5306)
					(mid 0 3.5306)
					(end 0 -3.5306)
				)
			)
			(stroke
				(width 0)
				(type default)
			)
			(fill no)
			(layer "B.CrtYd")
		)
		(fp_poly
			(pts
				(arc
					(start 0 -5.0038)
					(mid 0 5.0038)
					(end 0 -5.0038)
				)
			)
			(stroke
				(width 0)
				(type default)
			)
			(fill no)
			(layer "F.CrtYd")
		)
		(fp_poly
			(pts
				(arc
					(start 5.5118 0.00635)
					(mid -5.511804 0)
					(end 5.5118 -0.00635)
				)
				(arc
					(start 5.0038 -0.00635)
					(mid -5.003804 0)
					(end 5.0038 0.00635)
				)
			)
			(stroke
				(width 0)
				(type default)
			)
			(fill no)
			(layer "F.CrtYd")
		)
		(fp_poly
			(pts
				(arc
					(start 0 -3.5306)
					(mid 0 3.5306)
					(end 0 -3.5306)
				)
			)
			(stroke
				(width 0)
				(type default)
			)
			(fill no)
			(layer "B.Fab")
		)
		(fp_poly
			(pts
				(arc
					(start 0 -5.5118)
					(mid 0 5.5118)
					(end 0 -5.5118)
				)
			)
			(stroke
				(width 0)
				(type default)
			)
			(fill no)
			(layer "F.Fab")
		)
		(pad "1" thru_hole circle
			(at 0 0 270)
			(size 9.2202 9.2202)
			(drill 5.6896)
			(layers "*.Cu" "*.Mask")
			(remove_unused_layers no)
			(net "GND")
			(clearance -1.2573)
			(thermal_gap 0.3302)
			(padstack
				(mode front_inner_back)
				(layer "Inner"
					(shape circle)
					(size 6.0452 6.0452)
					(clearance 0.3302)
				)
				(layer "B.Cu"
					(shape circle)
					(size 6.0452 6.0452)
					(clearance 0.3302)
				)
			)
		)
	)
	(footprint ""
		(layer "F.Cu")
		(at 17.1958 -24.003 90)
		(property "Reference" "R87"
			(at 0 0 90)
			(layer "F.SilkS")
			(hide yes)
			(effects
				(font
					(size 1.27 1.27)
				)
			)
		)
		(property "Value" "10R2F-L-GP"
			(at 0.064008 -3.993896 90)
			(unlocked yes)
			(layer "F.Fab")
			(hide yes)
			(effects
				(font
					(size 1.016 1.016)
					(thickness 0.1524)
				)
			)
		)
		(property "Device Type" "R402H14"
			(at 0.064008 -5.517896 90)
			(unlocked yes)
			(layer "F.Fab")
			(hide yes)
			(effects
				(font
					(size 1.016 1.016)
					(thickness 0.1524)
				)
			)
		)
		(duplicate_pad_numbers_are_jumpers no)
		(fp_line
			(start 0.508 -0.9398)
			(end -0.508 -0.9398)
			(stroke
				(width 0.1524)
				(type default)
			)
			(layer "F.SilkS")
		)
		(fp_line
			(start -0.508 -0.9398)
			(end -0.508 0.9398)
			(stroke
				(width 0.1524)
				(type default)
			)
			(layer "F.SilkS")
		)
		(fp_rect
			(start -0.508 0.9398)
			(end 0.508 -0.9398)
			(stroke
				(width 0)
				(type default)
			)
			(fill no)
			(layer "F.CrtYd")
		)
		(fp_rect
			(start -0.508 0.9398)
			(end 0.508 -0.9398)
			(stroke
				(width 0)
				(type default)
			)
			(fill no)
			(layer "F.Fab")
		)
		(pad "1" smd custom
			(at 0 -0.4445 90)
			(size 0.1397 0.1397)
			(layers "F.Cu" "F.Mask" "F.Paste")
			(net "P12V_SLOT3")
			(options
				(clearance outline)
				(anchor circle)
			)
			(primitives
				(gr_poly
					(pts
						(arc
							(start -0.1778 -0.2794)
							(mid -0.249642 -0.249642)
							(end -0.2794 -0.1778)
						)
						(arc
							(start -0.2794 0.1778)
							(mid -0.249642 0.249642)
							(end -0.1778 0.2794)
						)
						(arc
							(start 0.1778 0.2794)
							(mid 0.249642 0.249642)
							(end 0.2794 0.1778)
						)
						(arc
							(start 0.2794 -0.1778)
							(mid 0.249642 -0.249642)
							(end 0.1778 -0.2794)
						)
					)
					(width 0)
					(fill yes)
				)
			)
		)
		(pad "2" smd custom
			(at 0 0.4445 90)
			(size 0.1397 0.1397)
			(layers "F.Cu" "F.Mask" "F.Paste")
			(net "SLOT3_P12V_SENSE_VN_R")
			(options
				(clearance outline)
				(anchor circle)
			)
			(primitives
				(gr_poly
					(pts
						(arc
							(start -0.1778 -0.2794)
							(mid -0.249642 -0.249642)
							(end -0.2794 -0.1778)
						)
						(arc
							(start -0.2794 0.1778)
							(mid -0.249642 0.249642)
							(end -0.1778 0.2794)
						)
						(arc
							(start 0.1778 0.2794)
							(mid 0.249642 0.249642)
							(end 0.2794 0.1778)
						)
						(arc
							(start 0.2794 -0.1778)
							(mid 0.249642 -0.249642)
							(end 0.1778 -0.2794)
						)
					)
					(width 0)
					(fill yes)
				)
			)
		)
	)
	(footprint ""
		(layer "F.Cu")
		(at 22.2504 -27.0002 -90)
		(property "Reference" "U15"
			(at 0 0 270)
			(layer "F.SilkS")
			(hide yes)
			(effects
				(font
					(size 1.27 1.27)
				)
			)
		)
		(property "Value" "INA230AIRGTR-GP"
			(at -5.6388 -6.1468 270)
			(unlocked yes)
			(layer "F.Fab")
			(hide yes)
			(effects
				(font
					(size 1.016 1.016)
					(thickness 0.1524)
				)
			)
		)
		(property "Device Type" "QFN16-G1D8-UH40"
			(at -5.6388 -7.6708 270)
			(unlocked yes)
			(layer "F.Fab")
			(hide yes)
			(effects
				(font
					(size 1.016 1.016)
					(thickness 0.1524)
				)
			)
		)
		(duplicate_pad_numbers_are_jumpers no)
		(fp_line
			(start -2.5146 2.5146)
			(end -1.2446 2.5146)
			(stroke
				(width 0.1524)
				(type default)
			)
			(layer "F.SilkS")
		)
		(fp_line
			(start 1.2446 2.5146)
			(end 2.5146 2.5146)
			(stroke
				(width 0.1524)
				(type default)
			)
			(layer "F.SilkS")
		)
		(fp_line
			(start 2.5146 2.5146)
			(end 2.5146 1.2446)
			(stroke
				(width 0.1524)
				(type default)
			)
			(layer "F.SilkS")
		)
		(fp_line
			(start -0.248666 2.287524)
			(end -0.248666 3.049524)
			(stroke
				(width 0.1524)
				(type default)
			)
			(layer "F.SilkS")
		)
		(fp_line
			(start -2.5146 1.2446)
			(end -2.5146 2.5146)
			(stroke
				(width 0.1524)
				(type default)
			)
			(layer "F.SilkS")
		)
		(fp_line
			(start 2.287524 -0.260604)
			(end 2.795524 -0.260604)
			(stroke
				(width 0.1524)
				(type default)
			)
			(layer "F.SilkS")
		)
		(fp_line
			(start -2.287524 -0.753364)
			(end -2.795524 -0.753364)
			(stroke
				(width 0.1524)
				(type default)
			)
			(layer "F.SilkS")
		)
		(fp_line
			(start -2.5146 -2.5146)
			(end -2.5146 -1.2446)
			(stroke
				(width 0.1524)
				(type default)
			)
			(layer "F.SilkS")
		)
		(fp_line
			(start -1.2446 -2.5146)
			(end -2.5146 -2.5146)
			(stroke
				(width 0.1524)
				(type default)
			)
			(layer "F.SilkS")
		)
		(fp_poly
			(pts
				(xy 1.2446 -2.5146) (xy 2.5146 -2.5146) (xy 2.5146 -1.2446)
			)
			(stroke
				(width 0)
				(type default)
			)
			(fill yes)
			(layer "F.SilkS")
		)
		(fp_rect
			(start -1.4986 1.4986)
			(end 1.4986 -1.4986)
			(stroke
				(width 0)
				(type default)
			)
			(fill no)
			(layer "F.CrtYd")
		)
		(fp_poly
			(pts
				(xy -1.4986 -1.4986) (xy -2.5146 -1.4986) (xy -2.5146 -2.5146) (xy 2.5146 -2.5146) (xy 2.5146 2.5146)
				(xy -2.5146 2.5146) (xy -2.5146 -1.4859) (xy -1.4986 -1.4859) (xy -1.4986 1.4986) (xy 1.4986 1.4986)
				(xy 1.4986 -1.4986)
			)
			(stroke
				(width 0)
				(type default)
			)
			(fill no)
			(layer "F.CrtYd")
		)
		(fp_rect
			(start -2.5146 2.5146)
			(end 2.5146 -2.5146)
			(stroke
				(width 0)
				(type default)
			)
			(fill no)
			(layer "F.Fab")
		)
		(pad "1" smd rect
			(at 0.750062 -1.550924 270)
			(size 0.3048 0.9144)
			(layers "F.Cu" "F.Mask" "F.Paste")
			(net "SLOT3_VMONITOR_A1")
		)
		(pad "2" smd rect
			(at 0.249936 -1.550924 270)
			(size 0.3048 0.9144)
			(layers "F.Cu" "F.Mask" "F.Paste")
			(net "SLOT3_VMONITOR_A0")
		)
		(pad "3" smd rect
			(at -0.249936 -1.550924 270)
			(size 0.3048 0.9144)
			(layers "F.Cu" "F.Mask" "F.Paste")
			(net "SMB_VMONITOR_SLOT3_ALERT_N")
		)
		(pad "4" smd rect
			(at -0.750062 -1.550924 270)
			(size 0.3048 0.9144)
			(layers "F.Cu" "F.Mask" "F.Paste")
			(net "SMB_VMONITOR_SLOT3_MUX_SDA")
		)
		(pad "5" smd rect
			(at -1.550924 -0.750062 270)
			(size 0.9144 0.3048)
			(layers "F.Cu" "F.Mask" "F.Paste")
			(net "SMB_VMONITOR_SLOT3_MUX_SCL")
		)
		(pad "6" smd rect
			(at -1.550924 -0.249936 270)
			(size 0.9144 0.3048)
			(layers "F.Cu" "F.Mask" "F.Paste")
			(net "Net_220")
		)
		(pad "7" smd rect
			(at -1.550924 0.249936 270)
			(size 0.9144 0.3048)
			(layers "F.Cu" "F.Mask" "F.Paste")
			(net "Net_221")
		)
		(pad "8" smd rect
			(at -1.550924 0.750062 270)
			(size 0.9144 0.3048)
			(layers "F.Cu" "F.Mask" "F.Paste")
			(net "Net_222")
		)
		(pad "9" smd rect
			(at -0.750062 1.550924 270)
			(size 0.3048 0.9144)
			(layers "F.Cu" "F.Mask" "F.Paste")
			(net "P3V3_STBY")
		)
		(pad "10" smd rect
			(at -0.249936 1.550924 270)
			(size 0.3048 0.9144)
			(layers "F.Cu" "F.Mask" "F.Paste")
			(net "GND")
		)
		(pad "11" smd rect
			(at 0.249936 1.550924 270)
			(size 0.3048 0.9144)
			(layers "F.Cu" "F.Mask" "F.Paste")
			(net "P12V")
		)
		(pad "12" smd rect
			(at 0.750062 1.550924 270)
			(size 0.3048 0.9144)
			(layers "F.Cu" "F.Mask" "F.Paste")
			(net "SLOT3_P12V_SENSE_VN_R")
		)
		(pad "13" smd rect
			(at 1.550924 0.750062 270)
			(size 0.9144 0.3048)
			(layers "F.Cu" "F.Mask" "F.Paste")
			(net "SLOT3_P12V_SENSE_VP_R")
		)
		(pad "14" smd rect
			(at 1.550924 0.249936 270)
			(size 0.9144 0.3048)
			(layers "F.Cu" "F.Mask" "F.Paste")
			(net "Net_217")
		)
		(pad "15" smd rect
			(at 1.550924 -0.249936 270)
			(size 0.9144 0.3048)
			(layers "F.Cu" "F.Mask" "F.Paste")
			(net "Net_218")
		)
		(pad "16" smd rect
			(at 1.550924 -0.750062 270)
			(size 0.9144 0.3048)
			(layers "F.Cu" "F.Mask" "F.Paste")
			(net "Net_219")
		)
		(pad "17" smd rect
			(at 0 0 270)
			(size 1.778 1.778)
			(layers "F.Cu" "F.Mask" "F.Paste")
			(net "GND")
		)
	)
	(footprint ""
		(layer "F.Cu")
		(at 123.9266 -0.0508 180)
		(property "Reference" "R140"
			(at 0 0 180)
			(layer "F.SilkS")
			(hide yes)
			(effects
				(font
					(size 1.27 1.27)
				)
			)
		)
		(property "Value" "10KR2F-2-GP"
			(at 0.064008 -3.993896 180)
			(unlocked yes)
			(layer "F.Fab")
			(hide yes)
			(effects
				(font
					(size 1.016 1.016)
					(thickness 0.1524)
				)
			)
		)
		(property "Device Type" "R402H16"
			(at 0.064008 -5.517896 180)
			(unlocked yes)
			(layer "F.Fab")
			(hide yes)
			(effects
				(font
					(size 1.016 1.016)
					(thickness 0.1524)
				)
			)
		)
		(duplicate_pad_numbers_are_jumpers no)
		(fp_line
			(start 0.508 -0.9398)
			(end -0.508 -0.9398)
			(stroke
				(width 0.1524)
				(type default)
			)
			(layer "F.SilkS")
		)
		(fp_line
			(start -0.508 -0.9398)
			(end -0.508 0.9398)
			(stroke
				(width 0.1524)
				(type default)
			)
			(layer "F.SilkS")
		)
		(fp_rect
			(start -0.508 0.9398)
			(end 0.508 -0.9398)
			(stroke
				(width 0)
				(type default)
			)
			(fill no)
			(layer "F.CrtYd")
		)
		(fp_rect
			(start -0.508 0.9398)
			(end 0.508 -0.9398)
			(stroke
				(width 0)
				(type default)
			)
			(fill no)
			(layer "F.Fab")
		)
		(pad "1" smd custom
			(at 0 -0.4445 180)
			(size 0.1397 0.1397)
			(layers "F.Cu" "F.Mask" "F.Paste")
			(net "P3V3_STBY")
			(options
				(clearance outline)
				(anchor circle)
			)
			(primitives
				(gr_poly
					(pts
						(arc
							(start -0.1778 -0.2794)
							(mid -0.249642 -0.249642)
							(end -0.2794 -0.1778)
						)
						(arc
							(start -0.2794 0.1778)
							(mid -0.249642 0.249642)
							(end -0.1778 0.2794)
						)
						(arc
							(start 0.1778 0.2794)
							(mid 0.249642 0.249642)
							(end 0.2794 0.1778)
						)
						(arc
							(start 0.2794 -0.1778)
							(mid 0.249642 -0.249642)
							(end 0.1778 -0.2794)
						)
					)
					(width 0)
					(fill yes)
				)
			)
		)
		(pad "2" smd custom
			(at 0 0.4445 180)
			(size 0.1397 0.1397)
			(layers "F.Cu" "F.Mask" "F.Paste")
			(net "GPIO_P_IO1_5")
			(options
				(clearance outline)
				(anchor circle)
			)
			(primitives
				(gr_poly
					(pts
						(arc
							(start -0.1778 -0.2794)
							(mid -0.249642 -0.249642)
							(end -0.2794 -0.1778)
						)
						(arc
							(start -0.2794 0.1778)
							(mid -0.249642 0.249642)
							(end -0.1778 0.2794)
						)
						(arc
							(start 0.1778 0.2794)
							(mid 0.249642 0.249642)
							(end 0.2794 0.1778)
						)
						(arc
							(start 0.2794 -0.1778)
							(mid 0.249642 -0.249642)
							(end 0.1778 -0.2794)
						)
					)
					(width 0)
					(fill yes)
				)
			)
		)
	)
)
